# BASEBOARD_FAB2 (Tioga Pass) — schematic netlist excerpt (pin names and nets, part order shuffled) for the footprints in the layout excerpt that follows; sources: Cadence DE-HDL packaged netlist, KiCad conversion of Wiwynn_Tioga_Pass_MB.brd

EU4A3  NCP3232L  IC  pkg SM  page 234
  SS  = VR_PVPP_KLM_SS
  FB  = VR_FB_PVPP_KLM
  COMP  = VR_COMP_PVPP_KLM_3
  ISET  = VR_PVPP_KLM_ISET
  AGND  = AGND_PVPP_KLM
  OTS  = AGND_PVPP_KLM
  PG  = PWRGD_PVPP_KLM_R
  VIN(0)  = VR_FET_SW_P12V_STBY_PVPP_KLM
  VIN(1)  = VR_FET_SW_P12V_STBY_PVPP_KLM
  VIN(2)  = VR_FET_SW_P12V_STBY_PVPP_KLM
  VIN(3)  = VR_FET_SW_P12V_STBY_PVPP_KLM
  VIN(4)  = VR_FET_SW_P12V_STBY_PVPP_KLM
  VIN(5)  = VR_FET_SW_P12V_STBY_PVPP_KLM
  VIN(6)  = VR_FET_SW_P12V_STBY_PVPP_KLM
  VSWH(0)  = VR_PVPP_KLM_PHASE
  PGND(0)  = GND
  PGND(1)  = GND
  PGND(2)  = GND
  PGND(3)  = GND
  PGND(4)  = GND
  PGND(5)  = GND
  PGND(6)  = GND
  PGND(7)  = GND
  PGND(8)  = GND
  PGND(9)  = GND
  PGND(10)  = GND
  PGND(11)  = GND
  PGND(12)  = GND
  VSWH(1)  = VR_PVPP_KLM_PHASE
  VSWH(2)  = VR_PVPP_KLM_PHASE
  VSWH(3)  = VR_PVPP_KLM_PHASE
  VSWH(4)  = VR_PVPP_KLM_PHASE
  VSWH(5)  = VR_PVPP_KLM_PHASE
  VSWH(6)  = VR_PVPP_KLM_PHASE
  VSW  = VR_PVPP_KLM_PHASE
  BST  = VR_PVPP_KLM_BOOT
  PGND(13)  = GND
  VB  = VR_VB_PVPP_KLM
  VCC  = VR_FET_SW_P12V_STBY_PVPP_KLM
  EN  = FM_PVPP_PVDDQ_CPU1_EN_KLM
  GND  = GND
  VIN(7)  = VR_FET_SW_P12V_STBY_PVPP_KLM
  VSWH(7)  = VR_PVPP_KLM_PHASE

(kicad_pcb
	(version 20260206)
	(generator "pcbnew")
	(generator_version "10.0")
	(general
		(thickness 1.6)
		(legacy_teardrops no)
	)
	(paper "A4")
	(title_block
		(title "Wiwynn_Tioga_Pass_MB.brd")
		(comment 1 "Tioga Pass / footprint 2008 of 4770 (EU4A3), pads 18-35 of 43")
	)
	(layers
		(0 "F.Cu" signal "TOP")
		(4 "In1.Cu" signal "L2GND")
		(6 "In2.Cu" signal "L3")
		(8 "In3.Cu" signal "L4GND")
		(10 "In4.Cu" signal "L5")
		(12 "In5.Cu" signal "L6GND")
		(14 "In6.Cu" signal "L7VCC")
		(16 "In7.Cu" signal "L8VCC")
		(18 "In8.Cu" signal "L9GND")
		(20 "In9.Cu" signal "L10")
		(22 "In10.Cu" signal "L11GND")
		(24 "In11.Cu" signal "L12")
		(26 "In12.Cu" signal "L13GND")
		(2 "B.Cu" signal "BOTTOM")
		(9 "F.Adhes" user "F.Adhesive")
		(11 "B.Adhes" user "B.Adhesive")
		(13 "F.Paste" user "Package Geometry/Pastemask Top")
		(15 "B.Paste" user "Package Geometry/Pastemask Bottom")
		(5 "F.SilkS" user "Ref Des/Silkscreen Top")
		(7 "B.SilkS" user "Ref Des/Silkscreen Bottom")
		(1 "F.Mask" user "Board Geometry/Soldermask Top")
		(3 "B.Mask" user "Board Geometry/Soldermask Bottom")
		(17 "Dwgs.User" user "User.Drawings")
		(19 "Cmts.User" user "User.Comments")
		(21 "Eco1.User" user "User.Eco1")
		(23 "Eco2.User" user "User.Eco2")
		(25 "Edge.Cuts" user "Board Geometry/Outline")
		(27 "Margin" user)
		(31 "F.CrtYd" user "Package Geometry/Place Bound Top")
		(29 "B.CrtYd" user "Package Geometry/Place Bound Bottom")
		(35 "F.Fab" user "Ref Des/Assembly Top")
		(33 "B.Fab" user "Ref Des/Assembly Bottom")
	)
	(footprint ""
		(layer "F.Cu")
		(at 177.673 -136.8425 90)
		(property "Reference" "EU4A3"
			(at 5.29463 0.1778 0)
			(unlocked yes)
			(layer "F.SilkS")
			(effects
				(font
					(size 0.7874 0.5842)
					(thickness 0.1524)
				)
				(justify left)
			)
		)
		(property "Value" ""
			(at 0 0 90)
			(layer "F.Fab")
			(effects
				(font
					(size 1.27 1.27)
				)
			)
		)
		(duplicate_pad_numbers_are_jumpers no)
		(pad "18" smd custom
			(at 1.249934 2.8321 90)
			(size 0.06985 0.06985)
			(layers "F.Cu" "F.Mask" "F.Paste")
			(net "GND")
			(options
				(clearance outline)
				(anchor circle)
			)
			(primitives
				(gr_poly
					(pts
						(arc
							(start -0.1397 -0.2413)
							(mid 0 -0.381)
							(end 0.1397 -0.2413)
						)
						(xy 0.1397 0.381) (xy -0.1397 0.381)
					)
					(width 0)
					(fill yes)
				)
			)
		)
		(pad "19" smd custom
			(at 1.75006 2.8321 90)
			(size 0.06985 0.06985)
			(layers "F.Cu" "F.Mask" "F.Paste")
			(net "GND")
			(options
				(clearance outline)
				(anchor circle)
			)
			(primitives
				(gr_poly
					(pts
						(arc
							(start -0.1397 -0.2413)
							(mid 0 -0.381)
							(end 0.1397 -0.2413)
						)
						(xy 0.1397 0.381) (xy -0.1397 0.381)
					)
					(width 0)
					(fill yes)
				)
			)
		)
		(pad "20" smd custom
			(at 2.249932 2.8321 90)
			(size 0.06985 0.06985)
			(layers "F.Cu" "F.Mask" "F.Paste")
			(net "GND")
			(options
				(clearance outline)
				(anchor circle)
			)
			(primitives
				(gr_poly
					(pts
						(arc
							(start -0.1397 -0.2413)
							(mid 0 -0.381)
							(end 0.1397 -0.2413)
						)
						(xy 0.1397 0.381) (xy -0.1397 0.381)
					)
					(width 0)
					(fill yes)
				)
			)
		)
		(pad "21" smd custom
			(at 2.8321 2.249932 90)
			(size 0.06985 0.06985)
			(layers "F.Cu" "F.Mask" "F.Paste")
			(net "GND")
			(options
				(clearance outline)
				(anchor circle)
			)
			(primitives
				(gr_poly
					(pts
						(arc
							(start -0.2413 0.1397)
							(mid -0.381 0)
							(end -0.2413 -0.1397)
						)
						(xy 0.381 -0.1397) (xy 0.381 0.1397)
					)
					(width 0)
					(fill yes)
				)
			)
		)
		(pad "22" smd custom
			(at 2.8321 1.75006 90)
			(size 0.06985 0.06985)
			(layers "F.Cu" "F.Mask" "F.Paste")
			(net "GND")
			(options
				(clearance outline)
				(anchor circle)
			)
			(primitives
				(gr_poly
					(pts
						(arc
							(start -0.2413 0.1397)
							(mid -0.381 0)
							(end -0.2413 -0.1397)
						)
						(xy 0.381 -0.1397) (xy 0.381 0.1397)
					)
					(width 0)
					(fill yes)
				)
			)
		)
		(pad "23" smd custom
			(at 2.8321 1.249934 90)
			(size 0.06985 0.06985)
			(layers "F.Cu" "F.Mask" "F.Paste")
			(net "GND")
			(options
				(clearance outline)
				(anchor circle)
			)
			(primitives
				(gr_poly
					(pts
						(arc
							(start -0.2413 0.1397)
							(mid -0.381 0)
							(end -0.2413 -0.1397)
						)
						(xy 0.381 -0.1397) (xy 0.381 0.1397)
					)
					(width 0)
					(fill yes)
				)
			)
		)
		(pad "24" smd custom
			(at 2.8321 0.750062 90)
			(size 0.06985 0.06985)
			(layers "F.Cu" "F.Mask" "F.Paste")
			(net "GND")
			(options
				(clearance outline)
				(anchor circle)
			)
			(primitives
				(gr_poly
					(pts
						(arc
							(start -0.2413 0.1397)
							(mid -0.381 0)
							(end -0.2413 -0.1397)
						)
						(xy 0.381 -0.1397) (xy 0.381 0.1397)
					)
					(width 0)
					(fill yes)
				)
			)
		)
		(pad "25" smd custom
			(at 2.8321 0.249936 90)
			(size 0.06985 0.06985)
			(layers "F.Cu" "F.Mask" "F.Paste")
			(net "GND")
			(options
				(clearance outline)
				(anchor circle)
			)
			(primitives
				(gr_poly
					(pts
						(arc
							(start -0.2413 0.1397)
							(mid -0.381 0)
							(end -0.2413 -0.1397)
						)
						(xy 0.381 -0.1397) (xy 0.381 0.1397)
					)
					(width 0)
					(fill yes)
				)
			)
		)
		(pad "26" smd custom
			(at 2.8321 -0.249936 90)
			(size 0.06985 0.06985)
			(layers "F.Cu" "F.Mask" "F.Paste")
			(net "GND")
			(options
				(clearance outline)
				(anchor circle)
			)
			(primitives
				(gr_poly
					(pts
						(arc
							(start -0.2413 0.1397)
							(mid -0.381 0)
							(end -0.2413 -0.1397)
						)
						(xy 0.381 -0.1397) (xy 0.381 0.1397)
					)
					(width 0)
					(fill yes)
				)
			)
		)
		(pad "27" smd custom
			(at 2.8321 -0.750062 90)
			(size 0.06985 0.06985)
			(layers "F.Cu" "F.Mask" "F.Paste")
			(net "GND")
			(options
				(clearance outline)
				(anchor circle)
			)
			(primitives
				(gr_poly
					(pts
						(arc
							(start -0.2413 0.1397)
							(mid -0.381 0)
							(end -0.2413 -0.1397)
						)
						(xy 0.381 -0.1397) (xy 0.381 0.1397)
					)
					(width 0)
					(fill yes)
				)
			)
		)
		(pad "28" smd custom
			(at 2.8321 -1.249934 90)
			(size 0.06985 0.06985)
			(layers "F.Cu" "F.Mask" "F.Paste")
			(net "GND")
			(options
				(clearance outline)
				(anchor circle)
			)
			(primitives
				(gr_poly
					(pts
						(arc
							(start -0.2413 0.1397)
							(mid -0.381 0)
							(end -0.2413 -0.1397)
						)
						(xy 0.381 -0.1397) (xy 0.381 0.1397)
					)
					(width 0)
					(fill yes)
				)
			)
		)
		(pad "29" smd custom
			(at 2.8321 -1.75006 90)
			(size 0.06985 0.06985)
			(layers "F.Cu" "F.Mask" "F.Paste")
			(net "VR_PVPP_KLM_PHASE")
			(options
				(clearance outline)
				(anchor circle)
			)
			(primitives
				(gr_poly
					(pts
						(arc
							(start -0.2413 0.1397)
							(mid -0.381 0)
							(end -0.2413 -0.1397)
						)
						(xy 0.381 -0.1397) (xy 0.381 0.1397)
					)
					(width 0)
					(fill yes)
				)
			)
		)
		(pad "30" smd custom
			(at 2.8321 -2.249932 90)
			(size 0.06985 0.06985)
			(layers "F.Cu" "F.Mask" "F.Paste")
			(net "VR_PVPP_KLM_PHASE")
			(options
				(clearance outline)
				(anchor circle)
			)
			(primitives
				(gr_poly
					(pts
						(arc
							(start -0.2413 0.1397)
							(mid -0.381 0)
							(end -0.2413 -0.1397)
						)
						(xy 0.381 -0.1397) (xy 0.381 0.1397)
					)
					(width 0)
					(fill yes)
				)
			)
		)
		(pad "31" smd custom
			(at 2.249932 -2.8321 90)
			(size 0.06985 0.06985)
			(layers "F.Cu" "F.Mask" "F.Paste")
			(net "VR_PVPP_KLM_PHASE")
			(options
				(clearance outline)
				(anchor circle)
			)
			(primitives
				(gr_poly
					(pts
						(arc
							(start 0.1397 0.2413)
							(mid 0 0.381)
							(end -0.1397 0.2413)
						)
						(xy -0.1397 -0.381) (xy 0.1397 -0.381)
					)
					(width 0)
					(fill yes)
				)
			)
		)
		(pad "32" smd custom
			(at 1.75006 -2.8321 90)
			(size 0.06985 0.06985)
			(layers "F.Cu" "F.Mask" "F.Paste")
			(net "VR_PVPP_KLM_PHASE")
			(options
				(clearance outline)
				(anchor circle)
			)
			(primitives
				(gr_poly
					(pts
						(arc
							(start 0.1397 0.2413)
							(mid 0 0.381)
							(end -0.1397 0.2413)
						)
						(xy -0.1397 -0.381) (xy 0.1397 -0.381)
					)
					(width 0)
					(fill yes)
				)
			)
		)
		(pad "33" smd custom
			(at 1.249934 -2.8321 90)
			(size 0.06985 0.06985)
			(layers "F.Cu" "F.Mask" "F.Paste")
			(net "VR_PVPP_KLM_PHASE")
			(options
				(clearance outline)
				(anchor circle)
			)
			(primitives
				(gr_poly
					(pts
						(arc
							(start 0.1397 0.2413)
							(mid 0 0.381)
							(end -0.1397 0.2413)
						)
						(xy -0.1397 -0.381) (xy 0.1397 -0.381)
					)
					(width 0)
					(fill yes)
				)
			)
		)
		(pad "34" smd custom
			(at 0.750062 -2.8321 90)
			(size 0.06985 0.06985)
			(layers "F.Cu" "F.Mask" "F.Paste")
			(net "VR_PVPP_KLM_PHASE")
			(options
				(clearance outline)
				(anchor circle)
			)
			(primitives
				(gr_poly
					(pts
						(arc
							(start 0.1397 0.2413)
							(mid 0 0.381)
							(end -0.1397 0.2413)
						)
						(xy -0.1397 -0.381) (xy 0.1397 -0.381)
					)
					(width 0)
					(fill yes)
				)
			)
		)
		(pad "35" smd custom
			(at 0.249936 -2.8321 90)
			(size 0.06985 0.06985)
			(layers "F.Cu" "F.Mask" "F.Paste")
			(net "VR_PVPP_KLM_PHASE")
			(options
				(clearance outline)
				(anchor circle)
			)
			(primitives
				(gr_poly
					(pts
						(arc
							(start 0.1397 0.2413)
							(mid 0 0.381)
							(end -0.1397 0.2413)
						)
						(xy -0.1397 -0.381) (xy 0.1397 -0.381)
					)
					(width 0)
					(fill yes)
				)
			)
		)
	)
)
